(kicad_pcb
	(version 20260206)
	(generator "pcbnew")
	(generator_version "10.0")
	(general
		(thickness 1.6)
		(legacy_teardrops no)
	)
	(paper "A4")
	(title_block
		(title "Wiwynn_Tioga_Pass_MB.brd")
		(comment 1 "Tioga Pass / footprints 4630-4636 of 4770")
	)
	(layers
		(0 "F.Cu" signal "TOP")
		(4 "In1.Cu" signal "L2GND")
		(6 "In2.Cu" signal "L3")
		(8 "In3.Cu" signal "L4GND")
		(10 "In4.Cu" signal "L5")
		(12 "In5.Cu" signal "L6GND")
		(14 "In6.Cu" signal "L7VCC")
		(16 "In7.Cu" signal "L8VCC")
		(18 "In8.Cu" signal "L9GND")
		(20 "In9.Cu" signal "L10")
		(22 "In10.Cu" signal "L11GND")
		(24 "In11.Cu" signal "L12")
		(26 "In12.Cu" signal "L13GND")
		(2 "B.Cu" signal "BOTTOM")
		(9 "F.Adhes" user "F.Adhesive")
		(11 "B.Adhes" user "B.Adhesive")
		(13 "F.Paste" user "Package Geometry/Pastemask Top")
		(15 "B.Paste" user "Package Geometry/Pastemask Bottom")
		(5 "F.SilkS" user "Ref Des/Silkscreen Top")
		(7 "B.SilkS" user "Ref Des/Silkscreen Bottom")
		(1 "F.Mask" user "Board Geometry/Soldermask Top")
		(3 "B.Mask" user "Board Geometry/Soldermask Bottom")
		(17 "Dwgs.User" user "User.Drawings")
		(19 "Cmts.User" user "User.Comments")
		(21 "Eco1.User" user "User.Eco1")
		(23 "Eco2.User" user "User.Eco2")
		(25 "Edge.Cuts" user "Board Geometry/Outline")
		(27 "Margin" user)
		(31 "F.CrtYd" user "Package Geometry/Place Bound Top")
		(29 "B.CrtYd" user "Package Geometry/Place Bound Bottom")
		(35 "F.Fab" user "Ref Des/Assembly Top")
		(33 "B.Fab" user "Ref Des/Assembly Bottom")
	)
	(footprint ""
		(layer "B.Cu")
		(at 180.1114 -76.2254 90)
		(property "Reference" "R6P18"
			(at 0 0 90)
			(layer "B.SilkS")
			(hide yes)
			(effects
				(font
					(size 1.27 1.27)
				)
				(justify mirror)
			)
		)
		(property "Value" ""
			(at 0 0 90)
			(layer "B.Fab")
			(effects
				(font
					(size 1.27 1.27)
				)
				(justify mirror)
			)
		)
		(duplicate_pad_numbers_are_jumpers no)
		(fp_poly
			(pts
				(xy 0.2794 -0.1016) (xy -0.2794 -0.1016) (xy -0.2794 0.9906) (xy 0.2794 0.9906)
			)
			(stroke
				(width 0)
				(type default)
			)
			(fill no)
			(layer "B.CrtYd")
		)
		(fp_line
			(start 0.2794 -0.1016)
			(end 0.2794 0.9906)
			(stroke
				(width 0.1)
				(type default)
			)
			(layer "B.Fab")
		)
		(fp_line
			(start -0.2794 -0.1016)
			(end 0.2794 -0.1016)
			(stroke
				(width 0.1)
				(type default)
			)
			(layer "B.Fab")
		)
		(fp_line
			(start 0.2794 0.9906)
			(end -0.2794 0.9906)
			(stroke
				(width 0.1)
				(type default)
			)
			(layer "B.Fab")
		)
		(fp_line
			(start -0.2794 0.9906)
			(end -0.2794 -0.1016)
			(stroke
				(width 0.1)
				(type default)
			)
			(layer "B.Fab")
		)
		(pad "1" smd rect
			(at 0 0 270)
			(size 0.508 0.508)
			(layers "B.Cu" "B.Mask" "B.Paste")
			(net "FM_PVCCIN_PVCCSA_CPU0_EN_LVC1")
		)
		(pad "2" smd rect
			(at 0 0.889 270)
			(size 0.508 0.508)
			(layers "B.Cu" "B.Mask" "B.Paste")
			(net "VR_PVCCIN_CPU0_VREN")
		)
		(zone
			(layer "B.Cu")
			(hatch none 0.5)
			(connect_pads
				(clearance 0)
			)
			(min_thickness 0.25)
			(keepout
				(tracks allowed)
				(vias not_allowed)
				(pads allowed)
				(copperpour not_allowed)
				(footprints allowed)
			)
			(placement
				(enabled no)
				(sheetname "")
			)
			(fill
				(thermal_gap 0.5)
				(thermal_bridge_width 0.5)
				(island_removal_mode 0)
			)
			(polygon
				(pts
					(xy 180.3654 -76.4794) (xy 180.3654 -75.9714) (xy 180.7464 -75.9714) (xy 180.7464 -76.4794)
				)
			)
		)
		(zone
			(layer "B.Cu")
			(hatch none 0.5)
			(connect_pads
				(clearance 0)
			)
			(min_thickness 0.25)
			(keepout
				(tracks not_allowed)
				(vias allowed)
				(pads allowed)
				(copperpour not_allowed)
				(footprints allowed)
			)
			(placement
				(enabled no)
				(sheetname "")
			)
			(fill
				(thermal_gap 0.5)
				(thermal_bridge_width 0.5)
				(island_removal_mode 0)
			)
			(polygon
				(pts
					(xy 180.7464 -76.4794) (xy 180.7464 -75.9714) (xy 180.3654 -75.9714) (xy 180.3654 -76.4794)
				)
			)
		)
	)
	(footprint ""
		(layer "B.Cu")
		(at 365.506 -78.3336 -90)
		(property "Reference" "R7D38"
			(at 0 0 90)
			(layer "B.SilkS")
			(hide yes)
			(effects
				(font
					(size 1.27 1.27)
				)
				(justify mirror)
			)
		)
		(property "Value" ""
			(at 0 0 90)
			(layer "B.Fab")
			(effects
				(font
					(size 1.27 1.27)
				)
				(justify mirror)
			)
		)
		(duplicate_pad_numbers_are_jumpers no)
		(fp_poly
			(pts
				(xy 0.2794 -0.1016) (xy -0.2794 -0.1016) (xy -0.2794 0.9906) (xy 0.2794 0.9906)
			)
			(stroke
				(width 0)
				(type default)
			)
			(fill no)
			(layer "B.CrtYd")
		)
		(fp_line
			(start -0.2794 0.9906)
			(end -0.2794 -0.1016)
			(stroke
				(width 0.1)
				(type default)
			)
			(layer "B.Fab")
		)
		(fp_line
			(start 0.2794 0.9906)
			(end -0.2794 0.9906)
			(stroke
				(width 0.1)
				(type default)
			)
			(layer "B.Fab")
		)
		(fp_line
			(start -0.2794 -0.1016)
			(end 0.2794 -0.1016)
			(stroke
				(width 0.1)
				(type default)
			)
			(layer "B.Fab")
		)
		(fp_line
			(start 0.2794 -0.1016)
			(end 0.2794 0.9906)
			(stroke
				(width 0.1)
				(type default)
			)
			(layer "B.Fab")
		)
		(pad "1" smd rect
			(at 0 0 90)
			(size 0.508 0.508)
			(layers "B.Cu" "B.Mask" "B.Paste")
			(net "FM_CPU1_VRM_OSC_EN")
		)
		(pad "2" smd rect
			(at 0 0.889 90)
			(size 0.508 0.508)
			(layers "B.Cu" "B.Mask" "B.Paste")
			(net "FM_CPU1_STL_BRD_OSC_EN")
		)
		(zone
			(layer "B.Cu")
			(hatch none 0.5)
			(connect_pads
				(clearance 0)
			)
			(min_thickness 0.25)
			(keepout
				(tracks not_allowed)
				(vias allowed)
				(pads allowed)
				(copperpour not_allowed)
				(footprints allowed)
			)
			(placement
				(enabled no)
				(sheetname "")
			)
			(fill
				(thermal_gap 0.5)
				(thermal_bridge_width 0.5)
				(island_removal_mode 0)
			)
			(polygon
				(pts
					(xy 364.871 -78.0796) (xy 364.871 -78.5876) (xy 365.252 -78.5876) (xy 365.252 -78.0796)
				)
			)
		)
		(zone
			(layer "B.Cu")
			(hatch none 0.5)
			(connect_pads
				(clearance 0)
			)
			(min_thickness 0.25)
			(keepout
				(tracks allowed)
				(vias not_allowed)
				(pads allowed)
				(copperpour not_allowed)
				(footprints allowed)
			)
			(placement
				(enabled no)
				(sheetname "")
			)
			(fill
				(thermal_gap 0.5)
				(thermal_bridge_width 0.5)
				(island_removal_mode 0)
			)
			(polygon
				(pts
					(xy 365.252 -78.0796) (xy 365.252 -78.5876) (xy 364.871 -78.5876) (xy 364.871 -78.0796)
				)
			)
		)
	)
	(footprint ""
		(layer "B.Cu")
		(at 422.91 -7.5565)
		(property "Reference" "C3P45"
			(at 0 0 0)
			(layer "B.SilkS")
			(hide yes)
			(effects
				(font
					(size 1.27 1.27)
				)
				(justify mirror)
			)
		)
		(property "Value" ""
			(at 0 0 0)
			(layer "B.Fab")
			(effects
				(font
					(size 1.27 1.27)
				)
				(justify mirror)
			)
		)
		(duplicate_pad_numbers_are_jumpers no)
		(fp_rect
			(start -0.3048 0.9906)
			(end 0.3048 -0.1016)
			(stroke
				(width 0)
				(type default)
			)
			(fill no)
			(layer "B.CrtYd")
		)
		(fp_line
			(start -0.3048 -0.1016)
			(end 0.3048 -0.1016)
			(stroke
				(width 0.1)
				(type default)
			)
			(layer "B.Fab")
		)
		(fp_line
			(start -0.3048 0.9906)
			(end -0.3048 -0.1016)
			(stroke
				(width 0.1)
				(type default)
			)
			(layer "B.Fab")
		)
		(fp_line
			(start 0.3048 -0.1016)
			(end 0.3048 0.9906)
			(stroke
				(width 0.1)
				(type default)
			)
			(layer "B.Fab")
		)
		(fp_line
			(start 0.3048 0.9906)
			(end -0.3048 0.9906)
			(stroke
				(width 0.1)
				(type default)
			)
			(layer "B.Fab")
		)
		(pad "1" smd rect
			(at 0 0 180)
			(size 0.508 0.508)
			(layers "B.Cu" "B.Mask" "B.Paste")
			(net "A_ADM1085_CEXT")
		)
		(pad "2" smd rect
			(at 0 0.889 180)
			(size 0.508 0.508)
			(layers "B.Cu" "B.Mask" "B.Paste")
			(net "GND")
		)
		(zone
			(layer "B.Cu")
			(hatch none 0.5)
			(connect_pads
				(clearance 0)
			)
			(min_thickness 0.25)
			(keepout
				(tracks allowed)
				(vias not_allowed)
				(pads allowed)
				(copperpour not_allowed)
				(footprints allowed)
			)
			(placement
				(enabled no)
				(sheetname "")
			)
			(fill
				(thermal_gap 0.5)
				(thermal_bridge_width 0.5)
				(island_removal_mode 0)
			)
			(polygon
				(pts
					(xy 422.656 -6.9215) (xy 423.164 -6.9215) (xy 423.164 -7.3025) (xy 422.656 -7.3025)
				)
			)
		)
		(zone
			(layer "B.Cu")
			(hatch none 0.5)
			(connect_pads
				(clearance 0)
			)
			(min_thickness 0.25)
			(keepout
				(tracks not_allowed)
				(vias allowed)
				(pads allowed)
				(copperpour not_allowed)
				(footprints allowed)
			)
			(placement
				(enabled no)
				(sheetname "")
			)
			(fill
				(thermal_gap 0.5)
				(thermal_bridge_width 0.5)
				(island_removal_mode 0)
			)
			(polygon
				(pts
					(xy 422.656 -6.9215) (xy 423.164 -6.9215) (xy 423.164 -7.3025) (xy 422.656 -7.3025)
				)
			)
		)
	)
	(footprint ""
		(layer "B.Cu")
		(at 365.506 -115.189 -90)
		(property "Reference" "C3M37"
			(at 0 0 90)
			(layer "B.SilkS")
			(hide yes)
			(effects
				(font
					(size 1.27 1.27)
				)
				(justify mirror)
			)
		)
		(property "Value" ""
			(at 0 0 90)
			(layer "B.Fab")
			(effects
				(font
					(size 1.27 1.27)
				)
				(justify mirror)
			)
		)
		(duplicate_pad_numbers_are_jumpers no)
		(fp_poly
			(pts
				(xy -0.3048 -0.1016) (xy -0.3048 0.9906) (xy 0.3048 0.9906) (xy 0.3048 -0.1016)
			)
			(stroke
				(width 0)
				(type default)
			)
			(fill no)
			(layer "B.CrtYd")
		)
		(fp_line
			(start -0.3048 0.9906)
			(end -0.3048 -0.1016)
			(stroke
				(width 0.1)
				(type default)
			)
			(layer "B.Fab")
		)
		(fp_line
			(start 0.3048 0.9906)
			(end -0.3048 0.9906)
			(stroke
				(width 0.1)
				(type default)
			)
			(layer "B.Fab")
		)
		(fp_line
			(start -0.3048 -0.1016)
			(end 0.3048 -0.1016)
			(stroke
				(width 0.1)
				(type default)
			)
			(layer "B.Fab")
		)
		(fp_line
			(start 0.3048 -0.1016)
			(end 0.3048 0.9906)
			(stroke
				(width 0.1)
				(type default)
			)
			(layer "B.Fab")
		)
		(pad "1" smd rect
			(at 0 0 90)
			(size 0.508 0.508)
			(layers "B.Cu" "B.Mask" "B.Paste")
			(net "DMI_CPU0_PCH_RX_DP<1>")
		)
		(pad "2" smd rect
			(at 0 0.889 90)
			(size 0.508 0.508)
			(layers "B.Cu" "B.Mask" "B.Paste")
			(net "DMI_CPU0_PCH_RX_C_DP<1>")
		)
		(zone
			(layer "B.Cu")
			(hatch none 0.5)
			(connect_pads
				(clearance 0)
			)
			(min_thickness 0.25)
			(keepout
				(tracks not_allowed)
				(vias allowed)
				(pads allowed)
				(copperpour not_allowed)
				(footprints allowed)
			)
			(placement
				(enabled no)
				(sheetname "")
			)
			(fill
				(thermal_gap 0.5)
				(thermal_bridge_width 0.5)
				(island_removal_mode 0)
			)
			(polygon
				(pts
					(xy 364.871 -114.935) (xy 364.871 -115.443) (xy 365.252 -115.443) (xy 365.252 -114.935)
				)
			)
		)
		(zone
			(layer "B.Cu")
			(hatch none 0.5)
			(connect_pads
				(clearance 0)
			)
			(min_thickness 0.25)
			(keepout
				(tracks allowed)
				(vias not_allowed)
				(pads allowed)
				(copperpour not_allowed)
				(footprints allowed)
			)
			(placement
				(enabled no)
				(sheetname "")
			)
			(fill
				(thermal_gap 0.5)
				(thermal_bridge_width 0.5)
				(island_removal_mode 0)
			)
			(polygon
				(pts
					(xy 365.252 -114.935) (xy 365.252 -115.443) (xy 364.871 -115.443) (xy 364.871 -114.935)
				)
			)
		)
	)
	(footprint ""
		(layer "B.Cu")
		(at 353.367848 -89.98204 180)
		(property "Reference" "R3N20"
			(at 0 0 0)
			(layer "B.SilkS")
			(hide yes)
			(effects
				(font
					(size 1.27 1.27)
				)
				(justify mirror)
			)
		)
		(property "Value" ""
			(at 0 0 0)
			(layer "B.Fab")
			(effects
				(font
					(size 1.27 1.27)
				)
				(justify mirror)
			)
		)
		(duplicate_pad_numbers_are_jumpers no)
		(fp_poly
			(pts
				(xy 0.2794 -0.1016) (xy -0.2794 -0.1016) (xy -0.2794 0.9906) (xy 0.2794 0.9906)
			)
			(stroke
				(width 0)
				(type default)
			)
			(fill no)
			(layer "B.CrtYd")
		)
		(fp_line
			(start 0.2794 0.9906)
			(end -0.2794 0.9906)
			(stroke
				(width 0.1)
				(type default)
			)
			(layer "B.Fab")
		)
		(fp_line
			(start 0.2794 -0.1016)
			(end 0.2794 0.9906)
			(stroke
				(width 0.1)
				(type default)
			)
			(layer "B.Fab")
		)
		(fp_line
			(start -0.2794 0.9906)
			(end -0.2794 -0.1016)
			(stroke
				(width 0.1)
				(type default)
			)
			(layer "B.Fab")
		)
		(fp_line
			(start -0.2794 -0.1016)
			(end 0.2794 -0.1016)
			(stroke
				(width 0.1)
				(type default)
			)
			(layer "B.Fab")
		)
		(pad "1" smd rect
			(at 0 0)
			(size 0.508 0.508)
			(layers "B.Cu" "B.Mask" "B.Paste")
			(net "VSENSE_PVCCIO_CPU0_AVSN")
		)
		(pad "2" smd rect
			(at 0 0.889)
			(size 0.508 0.508)
			(layers "B.Cu" "B.Mask" "B.Paste")
			(net "GND")
		)
		(zone
			(layer "B.Cu")
			(hatch none 0.5)
			(connect_pads
				(clearance 0)
			)
			(min_thickness 0.25)
			(keepout
				(tracks not_allowed)
				(vias allowed)
				(pads allowed)
				(copperpour not_allowed)
				(footprints allowed)
			)
			(placement
				(enabled no)
				(sheetname "")
			)
			(fill
				(thermal_gap 0.5)
				(thermal_bridge_width 0.5)
				(island_removal_mode 0)
			)
			(polygon
				(pts
					(xy 353.113848 -90.61704) (xy 353.621848 -90.61704) (xy 353.621848 -90.23604) (xy 353.113848 -90.23604)
				)
			)
		)
		(zone
			(layer "B.Cu")
			(hatch none 0.5)
			(connect_pads
				(clearance 0)
			)
			(min_thickness 0.25)
			(keepout
				(tracks allowed)
				(vias not_allowed)
				(pads allowed)
				(copperpour not_allowed)
				(footprints allowed)
			)
			(placement
				(enabled no)
				(sheetname "")
			)
			(fill
				(thermal_gap 0.5)
				(thermal_bridge_width 0.5)
				(island_removal_mode 0)
			)
			(polygon
				(pts
					(xy 353.113848 -90.23604) (xy 353.621848 -90.23604) (xy 353.621848 -90.61704) (xy 353.113848 -90.61704)
				)
			)
		)
	)
	(footprint ""
		(layer "B.Cu")
		(at 17.83842 -99.71532 90)
		(property "Reference" "C9N15"
			(at 0 0 90)
			(layer "B.SilkS")
			(hide yes)
			(effects
				(font
					(size 1.27 1.27)
				)
				(justify mirror)
			)
		)
		(property "Value" ""
			(at 0 0 90)
			(layer "B.Fab")
			(effects
				(font
					(size 1.27 1.27)
				)
				(justify mirror)
			)
		)
		(duplicate_pad_numbers_are_jumpers no)
		(fp_poly
			(pts
				(xy -0.3048 -0.1016) (xy -0.3048 0.9906) (xy 0.3048 0.9906) (xy 0.3048 -0.1016)
			)
			(stroke
				(width 0)
				(type default)
			)
			(fill no)
			(layer "B.CrtYd")
		)
		(fp_line
			(start 0.3048 -0.1016)
			(end 0.3048 0.9906)
			(stroke
				(width 0.1)
				(type default)
			)
			(layer "B.Fab")
		)
		(fp_line
			(start -0.3048 -0.1016)
			(end 0.3048 -0.1016)
			(stroke
				(width 0.1)
				(type default)
			)
			(layer "B.Fab")
		)
		(fp_line
			(start 0.3048 0.9906)
			(end -0.3048 0.9906)
			(stroke
				(width 0.1)
				(type default)
			)
			(layer "B.Fab")
		)
		(fp_line
			(start -0.3048 0.9906)
			(end -0.3048 -0.1016)
			(stroke
				(width 0.1)
				(type default)
			)
			(layer "B.Fab")
		)
		(pad "1" smd rect
			(at 0 0 270)
			(size 0.508 0.508)
			(layers "B.Cu" "B.Mask" "B.Paste")
			(net "P3E_CPU1_PE3_MP_C_TXN<9>")
		)
		(pad "2" smd rect
			(at 0 0.889 270)
			(size 0.508 0.508)
			(layers "B.Cu" "B.Mask" "B.Paste")
			(net "P3E_CPU1_PE3_MP_TXN<9>")
		)
		(zone
			(layer "B.Cu")
			(hatch none 0.5)
			(connect_pads
				(clearance 0)
			)
			(min_thickness 0.25)
			(keepout
				(tracks allowed)
				(vias not_allowed)
				(pads allowed)
				(copperpour not_allowed)
				(footprints allowed)
			)
			(placement
				(enabled no)
				(sheetname "")
			)
			(fill
				(thermal_gap 0.5)
				(thermal_bridge_width 0.5)
				(island_removal_mode 0)
			)
			(polygon
				(pts
					(xy 18.09242 -99.96932) (xy 18.09242 -99.46132) (xy 18.47342 -99.46132) (xy 18.47342 -99.96932)
				)
			)
		)
		(zone
			(layer "B.Cu")
			(hatch none 0.5)
			(connect_pads
				(clearance 0)
			)
			(min_thickness 0.25)
			(keepout
				(tracks not_allowed)
				(vias allowed)
				(pads allowed)
				(copperpour not_allowed)
				(footprints allowed)
			)
			(placement
				(enabled no)
				(sheetname "")
			)
			(fill
				(thermal_gap 0.5)
				(thermal_bridge_width 0.5)
				(island_removal_mode 0)
			)
			(polygon
				(pts
					(xy 18.47342 -99.96932) (xy 18.47342 -99.46132) (xy 18.09242 -99.46132) (xy 18.09242 -99.96932)
				)
			)
		)
	)
	(footprint ""
		(layer "B.Cu")
		(at 334.518 -10.795 180)
		(property "Reference" "C3U1"
			(at -3.27533 3.683 270)
			(unlocked yes)
			(layer "B.SilkS")
			(effects
				(font
					(size 0.7874 0.5842)
					(thickness 0.1524)
				)
				(justify mirror)
			)
		)
		(property "Value" ""
			(at 0 0 0)
			(layer "B.Fab")
			(effects
				(font
					(size 1.27 1.27)
				)
				(justify mirror)
			)
		)
		(duplicate_pad_numbers_are_jumpers no)
		(fp_line
			(start 2.563114 1.633728)
			(end 1.6002 1.633728)
			(stroke
				(width 0.1524)
				(type default)
			)
			(layer "B.SilkS")
		)
		(fp_line
			(start 2.563114 -1.616456)
			(end 2.563114 1.633728)
			(stroke
				(width 0.1524)
				(type default)
			)
			(layer "B.SilkS")
		)
		(fp_line
			(start 2.286 7.366)
			(end 2.286 1.632712)
			(stroke
				(width 0.1524)
				(type default)
			)
			(layer "B.SilkS")
		)
		(fp_line
			(start 2.286 7.366)
			(end 1.60147 7.366)
			(stroke
				(width 0.1524)
				(type default)
			)
			(layer "B.SilkS")
		)
		(fp_line
			(start 1.6002 -1.616456)
			(end 2.563114 -1.616456)
			(stroke
				(width 0.1524)
				(type default)
			)
			(layer "B.SilkS")
		)
		(fp_line
			(start -1.6002 -1.616456)
			(end -2.504948 -1.616456)
			(stroke
				(width 0.1524)
				(type default)
			)
			(layer "B.SilkS")
		)
		(fp_line
			(start -2.286 7.366)
			(end -1.600708 7.366)
			(stroke
				(width 0.1524)
				(type default)
			)
			(layer "B.SilkS")
		)
		(fp_line
			(start -2.286 7.366)
			(end -2.286 1.63195)
			(stroke
				(width 0.1524)
				(type default)
			)
			(layer "B.SilkS")
		)
		(fp_line
			(start -2.504948 1.633728)
			(end -1.6002 1.633728)
			(stroke
				(width 0.1524)
				(type default)
			)
			(layer "B.SilkS")
		)
		(fp_line
			(start -2.504948 -1.616456)
			(end -2.504948 1.633728)
			(stroke
				(width 0.1524)
				(type default)
			)
			(layer "B.SilkS")
		)
		(fp_rect
			(start -2.286 -0.254)
			(end 2.286 7.366)
			(stroke
				(width 0)
				(type default)
			)
			(fill no)
			(layer "B.CrtYd")
		)
		(fp_line
			(start 2.286 7.366)
			(end 2.286 -0.254)
			(stroke
				(width 0.1)
				(type default)
			)
			(layer "B.Fab")
		)
		(fp_line
			(start 2.286 -0.254)
			(end -2.286 -0.254)
			(stroke
				(width 0.1)
				(type default)
			)
			(layer "B.Fab")
		)
		(fp_line
			(start -2.286 7.366)
			(end 2.286 7.366)
			(stroke
				(width 0.1)
				(type default)
			)
			(layer "B.Fab")
		)
		(fp_line
			(start -2.286 -0.254)
			(end -2.286 7.366)
			(stroke
				(width 0.1)
				(type default)
			)
			(layer "B.Fab")
		)
		(pad "1" smd rect
			(at 0 0)
			(size 2.54 3.048)
			(layers "B.Cu" "B.Mask" "B.Paste")
			(net "PVDDQ_ABC")
		)
		(pad "2" smd rect
			(at 0 7.112)
			(size 2.54 3.048)
			(layers "B.Cu" "B.Mask" "B.Paste")
			(net "GND")
		)
	)
)
